# S9S_MB_2U (Grand Teton) — schematic netlist excerpt (pin names and nets, part order shuffled) for the footprints in the layout excerpt that follows; sources: Cadence DE-HDL packaged netlist, KiCad conversion of 03242023_DA0F0TMBIJ0_F0T_Motherboard_J_brd_V01_OCP.brd

PC28  Q_CAP  3300PF 50V 10% X7R  pkg 0402  page 300 : A = PVNN_MAIN_CPU1_REF ; B = GND

PL25  Q_INDUCTOR4P_14  150NH IND  pkg L_TLM117513Q-151QL_11X7-5XA  page 288
  \1\  = SW_PVCCIN_CPU1_SW7
  \2\  = IND_P1_CPL7
  \3\  = GND
  \4\  = PVCCIN_CPU1

(kicad_pcb
	(version 20260206)
	(generator "pcbnew")
	(generator_version "10.0")
	(general
		(thickness 1.6)
		(legacy_teardrops no)
	)
	(paper "A4")
	(title_block
		(title "03242023_DA0F0TMBIJ0_F0T_Motherboard_J_brd_V01_OCP.brd")
		(comment 1 "Grand Teton / footprints 570-571 of 6105")
	)
	(layers
		(0 "F.Cu" signal "TOP")
		(4 "In1.Cu" signal "GND")
		(6 "In2.Cu" signal "IN1")
		(8 "In3.Cu" signal "GND1")
		(10 "In4.Cu" signal "IN2")
		(12 "In5.Cu" signal "GND2")
		(14 "In6.Cu" signal "IN3")
		(16 "In7.Cu" signal "GND3")
		(18 "In8.Cu" signal "VCC")
		(20 "In9.Cu" signal "VCC1")
		(22 "In10.Cu" signal "GND4")
		(24 "In11.Cu" signal "IN4")
		(26 "In12.Cu" signal "GND5")
		(28 "In13.Cu" signal "IN5")
		(30 "In14.Cu" signal "GND6")
		(32 "In15.Cu" signal "IN6")
		(34 "In16.Cu" signal "GND7")
		(2 "B.Cu" signal "BOTTOM")
		(9 "F.Adhes" user "F.Adhesive")
		(11 "B.Adhes" user "B.Adhesive")
		(13 "F.Paste" user "Package Geometry/Pastemask Top")
		(15 "B.Paste" user "Package Geometry/Pastemask Bottom")
		(5 "F.SilkS" user "Ref Des/Silkscreen Top")
		(7 "B.SilkS" user "Ref Des/Silkscreen Bottom")
		(1 "F.Mask" user "Board Geometry/Soldermask Top")
		(3 "B.Mask" user "Board Geometry/Soldermask Bottom")
		(17 "Dwgs.User" user "User.Drawings")
		(19 "Cmts.User" user "User.Comments")
		(21 "Eco1.User" user "User.Eco1")
		(23 "Eco2.User" user "User.Eco2")
		(25 "Edge.Cuts" user "Board Geometry/Outline")
		(27 "Margin" user)
		(31 "F.CrtYd" user "Package Geometry/Place Bound Top")
		(29 "B.CrtYd" user "Package Geometry/Place Bound Bottom")
		(35 "F.Fab" user "Ref Des/Assembly Top")
		(33 "B.Fab" user "Ref Des/Assembly Bottom")
	)
	(footprint ""
		(layer "F.Cu")
		(at 24.71928 -176.850548 180)
		(property "Reference" "PC28"
			(at 0 0 180)
			(layer "F.SilkS")
			(hide yes)
			(effects
				(font
					(size 1.27 1.27)
				)
			)
		)
		(property "Value" ""
			(at 0 0 180)
			(layer "F.Fab")
			(effects
				(font
					(size 1.27 1.27)
				)
			)
		)
		(duplicate_pad_numbers_are_jumpers no)
		(fp_line
			(start 0.7874 0.4064)
			(end -0.7874 0.4064)
			(stroke
				(width 0.1524)
				(type default)
			)
			(layer "F.SilkS")
		)
		(fp_line
			(start 0.7874 -0.4064)
			(end 0.7874 0.4064)
			(stroke
				(width 0.1524)
				(type default)
			)
			(layer "F.SilkS")
		)
		(fp_line
			(start -0.7874 0.4064)
			(end -0.7874 -0.4064)
			(stroke
				(width 0.1524)
				(type default)
			)
			(layer "F.SilkS")
		)
		(fp_line
			(start -0.7874 -0.4064)
			(end 0.7874 -0.4064)
			(stroke
				(width 0.1524)
				(type default)
			)
			(layer "F.SilkS")
		)
		(fp_line
			(start 0.67945 0.3048)
			(end 0.120396 0.3048)
			(stroke
				(width 0.1)
				(type default)
			)
			(layer "F.Fab")
		)
		(fp_line
			(start 0.67945 -0.3048)
			(end 0.67945 0.3048)
			(stroke
				(width 0.1)
				(type default)
			)
			(layer "F.Fab")
		)
		(fp_line
			(start 0.12065 -0.2794)
			(end 0.12065 -0.3048)
			(stroke
				(width 0.1)
				(type default)
			)
			(layer "F.Fab")
		)
		(fp_line
			(start 0.12065 -0.3048)
			(end 0.67945 -0.3048)
			(stroke
				(width 0.1)
				(type default)
			)
			(layer "F.Fab")
		)
		(fp_line
			(start 0.120396 0.3048)
			(end 0.120396 0.2794)
			(stroke
				(width 0.1)
				(type default)
			)
			(layer "F.Fab")
		)
		(fp_line
			(start 0.120396 0.2794)
			(end -0.12065 0.2794)
			(stroke
				(width 0.1)
				(type default)
			)
			(layer "F.Fab")
		)
		(fp_line
			(start -0.12065 0.3048)
			(end -0.67945 0.3048)
			(stroke
				(width 0.1)
				(type default)
			)
			(layer "F.Fab")
		)
		(fp_line
			(start -0.12065 0.2794)
			(end -0.12065 0.3048)
			(stroke
				(width 0.1)
				(type default)
			)
			(layer "F.Fab")
		)
		(fp_line
			(start -0.12065 -0.2794)
			(end 0.12065 -0.2794)
			(stroke
				(width 0.1)
				(type default)
			)
			(layer "F.Fab")
		)
		(fp_line
			(start -0.12065 -0.305054)
			(end -0.12065 -0.2794)
			(stroke
				(width 0.1)
				(type default)
			)
			(layer "F.Fab")
		)
		(fp_line
			(start -0.67945 0.3048)
			(end -0.67945 -0.305054)
			(stroke
				(width 0.1)
				(type default)
			)
			(layer "F.Fab")
		)
		(fp_line
			(start -0.67945 -0.305054)
			(end -0.12065 -0.305054)
			(stroke
				(width 0.1)
				(type default)
			)
			(layer "F.Fab")
		)
		(pad "1" smd circle
			(at -0.40005 0 180)
			(size 0 0)
			(layers "F.Cu" "F.Mask" "F.Paste")
			(net "PVNN_MAIN_CPU1_REF")
		)
		(pad "2" smd circle
			(at 0.40005 0 180)
			(size 0 0)
			(layers "F.Cu" "F.Mask" "F.Paste")
			(net "GND")
		)
	)
	(footprint ""
		(layer "F.Cu")
		(at 80.681068 -333.61884)
		(property "Reference" "PL25"
			(at -2.416556 6.896354 0)
			(unlocked yes)
			(layer "F.SilkS")
			(effects
				(font
					(size 0.7874 0.5842)
					(thickness 0.1524)
				)
				(justify left)
			)
		)
		(property "Value" ""
			(at 0 0 0)
			(layer "F.Fab")
			(effects
				(font
					(size 1.27 1.27)
				)
			)
		)
		(duplicate_pad_numbers_are_jumpers no)
		(fp_line
			(start -3.750056 -5.500116)
			(end -2.393442 -5.500116)
			(stroke
				(width 0.1524)
				(type default)
			)
			(layer "F.SilkS")
		)
		(fp_line
			(start -3.750056 5.500116)
			(end -3.750056 -5.500116)
			(stroke
				(width 0.1524)
				(type default)
			)
			(layer "F.SilkS")
		)
		(fp_line
			(start -2.393442 5.500116)
			(end -3.750056 5.500116)
			(stroke
				(width 0.1524)
				(type default)
			)
			(layer "F.SilkS")
		)
		(fp_line
			(start 2.393442 5.500116)
			(end 3.750056 5.500116)
			(stroke
				(width 0.1524)
				(type default)
			)
			(layer "F.SilkS")
		)
		(fp_line
			(start 3.750056 -5.500116)
			(end 2.393442 -5.500116)
			(stroke
				(width 0.1524)
				(type default)
			)
			(layer "F.SilkS")
		)
		(fp_line
			(start 3.750056 5.500116)
			(end 3.750056 -5.500116)
			(stroke
				(width 0.1524)
				(type default)
			)
			(layer "F.SilkS")
		)
		(fp_poly
			(pts
				(xy -3.607054 -7.02945) (xy -3.247898 -5.951728) (xy -4.32562 -6.310884)
			)
			(stroke
				(width 0)
				(type default)
			)
			(fill yes)
			(layer "F.SilkS")
		)
		(fp_line
			(start -3.750056 -5.500116)
			(end -3.750056 5.500116)
			(stroke
				(width 0.1)
				(type default)
			)
			(layer "F.Fab")
		)
		(fp_line
			(start -3.750056 5.500116)
			(end 3.750056 5.500116)
			(stroke
				(width 0.1)
				(type default)
			)
			(layer "F.Fab")
		)
		(fp_line
			(start 3.750056 -5.500116)
			(end -3.750056 -5.500116)
			(stroke
				(width 0.1)
				(type default)
			)
			(layer "F.Fab")
		)
		(fp_line
			(start 3.750056 5.500116)
			(end 3.750056 -5.500116)
			(stroke
				(width 0.1)
				(type default)
			)
			(layer "F.Fab")
		)
		(fp_poly
			(pts
				(xy -4.9276 -4.757928) (xy -4.9276 -3.741928) (xy -3.9116 -4.249928)
			)
			(stroke
				(width 0)
				(type default)
			)
			(fill yes)
			(layer "F.Fab")
		)
		(pad "1" smd rect
			(at 0 -4.249928 270)
			(size 2.413 4.5212)
			(layers "F.Cu" "F.Mask" "F.Paste")
			(net "SW_PVCCIN_CPU1_SW7")
		)
		(pad "2" smd rect
			(at 0 -1.175004 270)
			(size 1.3716 4.5212)
			(layers "F.Cu" "F.Mask" "F.Paste")
			(net "IND_P1_CPL7")
		)
		(pad "3" smd rect
			(at 0 1.175004 270)
			(size 1.3716 4.5212)
			(layers "F.Cu" "F.Mask" "F.Paste")
			(net "GND")
		)
		(pad "4" smd rect
			(at 0 4.249928 270)
			(size 2.413 4.5212)
			(layers "F.Cu" "F.Mask" "F.Paste")
			(net "PVCCIN_CPU1")
		)
	)
)
